(kicad_pcb
	(version 20260206)
	(generator "pcbnew")
	(generator_version "10.0")
	(general
		(thickness 1.6)
		(legacy_teardrops no)
	)
	(paper "A4")
	(title_block
		(title "12092022_DA0F0TMDCD0_F0T_Management_Board_D_brd_V3_OCP.brd")
		(comment 1 "Grand Teton / footprints 845-850 of 1440")
	)
	(layers
		(0 "F.Cu" signal "TOP")
		(4 "In1.Cu" signal "GND")
		(6 "In2.Cu" signal "IN1")
		(8 "In3.Cu" signal "GND1")
		(10 "In4.Cu" signal "IN2")
		(12 "In5.Cu" signal "VCC")
		(14 "In6.Cu" signal "VCC1")
		(16 "In7.Cu" signal "IN3")
		(18 "In8.Cu" signal "GND2")
		(20 "In9.Cu" signal "IN4")
		(22 "In10.Cu" signal "GND3")
		(2 "B.Cu" signal "BOTTOM")
		(9 "F.Adhes" user "F.Adhesive")
		(11 "B.Adhes" user "B.Adhesive")
		(13 "F.Paste" user "Package Geometry/Pastemask Top")
		(15 "B.Paste" user "Package Geometry/Pastemask Bottom")
		(5 "F.SilkS" user "Ref Des/Silkscreen Top")
		(7 "B.SilkS" user "Ref Des/Silkscreen Bottom")
		(1 "F.Mask" user "Board Geometry/Soldermask Top")
		(3 "B.Mask" user "Board Geometry/Soldermask Bottom")
		(17 "Dwgs.User" user "User.Drawings")
		(19 "Cmts.User" user "User.Comments")
		(21 "Eco1.User" user "User.Eco1")
		(23 "Eco2.User" user "User.Eco2")
		(25 "Edge.Cuts" user "Board Geometry/Outline")
		(27 "Margin" user)
		(31 "F.CrtYd" user "Package Geometry/Place Bound Top")
		(29 "B.CrtYd" user "Package Geometry/Place Bound Bottom")
		(35 "F.Fab" user "Ref Des/Assembly Top")
		(33 "B.Fab" user "Ref Des/Assembly Bottom")
	)
	(footprint ""
		(layer "B.Cu")
		(at 74.8538 -33.4518 180)
		(property "Reference" "R674"
			(at 0 0 0)
			(layer "B.SilkS")
			(hide yes)
			(effects
				(font
					(size 1.27 1.27)
				)
				(justify mirror)
			)
		)
		(property "Value" ""
			(at 0 0 0)
			(layer "B.Fab")
			(effects
				(font
					(size 1.27 1.27)
				)
				(justify mirror)
			)
		)
		(duplicate_pad_numbers_are_jumpers no)
		(fp_line
			(start 0.7874 0.4064)
			(end 0.7874 -0.4064)
			(stroke
				(width 0.1524)
				(type default)
			)
			(layer "B.SilkS")
		)
		(fp_line
			(start 0.7874 -0.4064)
			(end -0.7874 -0.4064)
			(stroke
				(width 0.1524)
				(type default)
			)
			(layer "B.SilkS")
		)
		(fp_line
			(start -0.7874 0.4064)
			(end 0.7874 0.4064)
			(stroke
				(width 0.1524)
				(type default)
			)
			(layer "B.SilkS")
		)
		(fp_line
			(start -0.7874 -0.4064)
			(end -0.7874 0.4064)
			(stroke
				(width 0.1524)
				(type default)
			)
			(layer "B.SilkS")
		)
		(fp_line
			(start 0.67945 0.3048)
			(end 0.67945 -0.305054)
			(stroke
				(width 0.1)
				(type default)
			)
			(layer "B.Fab")
		)
		(fp_line
			(start 0.67945 -0.305054)
			(end 0.12065 -0.305054)
			(stroke
				(width 0.1)
				(type default)
			)
			(layer "B.Fab")
		)
		(fp_line
			(start 0.12065 0.3048)
			(end 0.67945 0.3048)
			(stroke
				(width 0.1)
				(type default)
			)
			(layer "B.Fab")
		)
		(fp_line
			(start 0.12065 0.2794)
			(end 0.12065 0.3048)
			(stroke
				(width 0.1)
				(type default)
			)
			(layer "B.Fab")
		)
		(fp_line
			(start 0.12065 -0.2794)
			(end -0.12065 -0.2794)
			(stroke
				(width 0.1)
				(type default)
			)
			(layer "B.Fab")
		)
		(fp_line
			(start 0.12065 -0.305054)
			(end 0.12065 -0.2794)
			(stroke
				(width 0.1)
				(type default)
			)
			(layer "B.Fab")
		)
		(fp_line
			(start -0.120396 0.3048)
			(end -0.120396 0.2794)
			(stroke
				(width 0.1)
				(type default)
			)
			(layer "B.Fab")
		)
		(fp_line
			(start -0.120396 0.2794)
			(end 0.12065 0.2794)
			(stroke
				(width 0.1)
				(type default)
			)
			(layer "B.Fab")
		)
		(fp_line
			(start -0.12065 -0.2794)
			(end -0.12065 -0.3048)
			(stroke
				(width 0.1)
				(type default)
			)
			(layer "B.Fab")
		)
		(fp_line
			(start -0.12065 -0.3048)
			(end -0.67945 -0.3048)
			(stroke
				(width 0.1)
				(type default)
			)
			(layer "B.Fab")
		)
		(fp_line
			(start -0.67945 0.3048)
			(end -0.120396 0.3048)
			(stroke
				(width 0.1)
				(type default)
			)
			(layer "B.Fab")
		)
		(fp_line
			(start -0.67945 -0.3048)
			(end -0.67945 0.3048)
			(stroke
				(width 0.1)
				(type default)
			)
			(layer "B.Fab")
		)
		(pad "1" smd circle
			(at 0.40005 0)
			(size 0 0)
			(layers "B.Cu" "B.Mask" "B.Paste")
			(net "LED_POSTCODE_6")
		)
		(pad "2" smd circle
			(at -0.40005 0)
			(size 0 0)
			(layers "B.Cu" "B.Mask" "B.Paste")
			(net "LED_POSTCODE_6_R1")
		)
	)
	(footprint ""
		(layer "B.Cu")
		(at 65.2018 -34.637726 90)
		(property "Reference" "R170"
			(at 0 0 90)
			(layer "B.SilkS")
			(hide yes)
			(effects
				(font
					(size 1.27 1.27)
				)
				(justify mirror)
			)
		)
		(property "Value" ""
			(at 0 0 90)
			(layer "B.Fab")
			(effects
				(font
					(size 1.27 1.27)
				)
				(justify mirror)
			)
		)
		(duplicate_pad_numbers_are_jumpers no)
		(fp_line
			(start 0.7874 -0.4064)
			(end -0.7874 -0.4064)
			(stroke
				(width 0.1524)
				(type default)
			)
			(layer "B.SilkS")
		)
		(fp_line
			(start -0.7874 -0.4064)
			(end -0.7874 0.4064)
			(stroke
				(width 0.1524)
				(type default)
			)
			(layer "B.SilkS")
		)
		(fp_line
			(start 0.7874 0.4064)
			(end 0.7874 -0.4064)
			(stroke
				(width 0.1524)
				(type default)
			)
			(layer "B.SilkS")
		)
		(fp_line
			(start -0.7874 0.4064)
			(end 0.7874 0.4064)
			(stroke
				(width 0.1524)
				(type default)
			)
			(layer "B.SilkS")
		)
		(fp_line
			(start 0.67945 -0.305054)
			(end 0.12065 -0.305054)
			(stroke
				(width 0.1)
				(type default)
			)
			(layer "B.Fab")
		)
		(fp_line
			(start 0.12065 -0.305054)
			(end 0.12065 -0.2794)
			(stroke
				(width 0.1)
				(type default)
			)
			(layer "B.Fab")
		)
		(fp_line
			(start -0.12065 -0.3048)
			(end -0.67945 -0.3048)
			(stroke
				(width 0.1)
				(type default)
			)
			(layer "B.Fab")
		)
		(fp_line
			(start -0.67945 -0.3048)
			(end -0.67945 0.3048)
			(stroke
				(width 0.1)
				(type default)
			)
			(layer "B.Fab")
		)
		(fp_line
			(start 0.12065 -0.2794)
			(end -0.12065 -0.2794)
			(stroke
				(width 0.1)
				(type default)
			)
			(layer "B.Fab")
		)
		(fp_line
			(start -0.12065 -0.2794)
			(end -0.12065 -0.3048)
			(stroke
				(width 0.1)
				(type default)
			)
			(layer "B.Fab")
		)
		(fp_line
			(start 0.12065 0.2794)
			(end 0.12065 0.3048)
			(stroke
				(width 0.1)
				(type default)
			)
			(layer "B.Fab")
		)
		(fp_line
			(start -0.120396 0.2794)
			(end 0.12065 0.2794)
			(stroke
				(width 0.1)
				(type default)
			)
			(layer "B.Fab")
		)
		(fp_line
			(start 0.67945 0.3048)
			(end 0.67945 -0.305054)
			(stroke
				(width 0.1)
				(type default)
			)
			(layer "B.Fab")
		)
		(fp_line
			(start 0.12065 0.3048)
			(end 0.67945 0.3048)
			(stroke
				(width 0.1)
				(type default)
			)
			(layer "B.Fab")
		)
		(fp_line
			(start -0.120396 0.3048)
			(end -0.120396 0.2794)
			(stroke
				(width 0.1)
				(type default)
			)
			(layer "B.Fab")
		)
		(fp_line
			(start -0.67945 0.3048)
			(end -0.120396 0.3048)
			(stroke
				(width 0.1)
				(type default)
			)
			(layer "B.Fab")
		)
		(pad "1" smd circle
			(at 0.40005 0 270)
			(size 0 0)
			(layers "B.Cu" "B.Mask" "B.Paste")
			(net "UART_BMC_5_TXD")
		)
		(pad "2" smd circle
			(at -0.40005 0 270)
			(size 0 0)
			(layers "B.Cu" "B.Mask" "B.Paste")
			(net "UART_BMC_5_TXD_R")
		)
	)
	(footprint ""
		(layer "B.Cu")
		(at 67.70878 -34.155126 -90)
		(property "Reference" "L4"
			(at 0 0 90)
			(layer "B.SilkS")
			(hide yes)
			(effects
				(font
					(size 1.27 1.27)
				)
				(justify mirror)
			)
		)
		(property "Value" ""
			(at 0 0 90)
			(layer "B.Fab")
			(effects
				(font
					(size 1.27 1.27)
				)
				(justify mirror)
			)
		)
		(duplicate_pad_numbers_are_jumpers no)
		(fp_line
			(start -1.27 0.5842)
			(end 1.27 0.5842)
			(stroke
				(width 0.1524)
				(type default)
			)
			(layer "B.SilkS")
		)
		(fp_line
			(start -1.27 0.5842)
			(end -1.27 -0.5842)
			(stroke
				(width 0.1524)
				(type default)
			)
			(layer "B.SilkS")
		)
		(fp_line
			(start -0.127 0.5842)
			(end -0.127 -0.5842)
			(stroke
				(width 0.1524)
				(type default)
			)
			(layer "B.SilkS")
		)
		(fp_line
			(start 0.127 0.5842)
			(end 0.127 -0.5842)
			(stroke
				(width 0.1524)
				(type default)
			)
			(layer "B.SilkS")
		)
		(fp_line
			(start 1.27 0.5842)
			(end 1.27 -0.5842)
			(stroke
				(width 0.1524)
				(type default)
			)
			(layer "B.SilkS")
		)
		(fp_line
			(start 1.27 -0.5588)
			(end 1.27 -0.5842)
			(stroke
				(width 0.1524)
				(type default)
			)
			(layer "B.SilkS")
		)
		(fp_line
			(start 1.27 -0.5842)
			(end -1.27 -0.5842)
			(stroke
				(width 0.1524)
				(type default)
			)
			(layer "B.SilkS")
		)
		(fp_line
			(start -0.9144 0.508)
			(end 0.9144 0.508)
			(stroke
				(width 0.1)
				(type default)
			)
			(layer "B.Fab")
		)
		(fp_line
			(start 0.9144 0.508)
			(end 0.9144 0.406654)
			(stroke
				(width 0.1)
				(type default)
			)
			(layer "B.Fab")
		)
		(fp_line
			(start 0.9144 0.406654)
			(end 1.194308 0.406654)
			(stroke
				(width 0.1)
				(type default)
			)
			(layer "B.Fab")
		)
		(fp_line
			(start 1.194308 0.406654)
			(end 1.194308 -0.406654)
			(stroke
				(width 0.1)
				(type default)
			)
			(layer "B.Fab")
		)
		(fp_line
			(start -1.1938 0.4064)
			(end -0.9144 0.4064)
			(stroke
				(width 0.1)
				(type default)
			)
			(layer "B.Fab")
		)
		(fp_line
			(start -0.9144 0.4064)
			(end -0.9144 0.508)
			(stroke
				(width 0.1)
				(type default)
			)
			(layer "B.Fab")
		)
		(fp_line
			(start -1.1938 -0.406654)
			(end -1.1938 0.4064)
			(stroke
				(width 0.1)
				(type default)
			)
			(layer "B.Fab")
		)
		(fp_line
			(start -0.9144 -0.406654)
			(end -1.1938 -0.406654)
			(stroke
				(width 0.1)
				(type default)
			)
			(layer "B.Fab")
		)
		(fp_line
			(start 0.9144 -0.406654)
			(end 0.9144 -0.508)
			(stroke
				(width 0.1)
				(type default)
			)
			(layer "B.Fab")
		)
		(fp_line
			(start 1.194308 -0.406654)
			(end 0.9144 -0.406654)
			(stroke
				(width 0.1)
				(type default)
			)
			(layer "B.Fab")
		)
		(fp_line
			(start -0.9144 -0.508)
			(end -0.9144 -0.406654)
			(stroke
				(width 0.1)
				(type default)
			)
			(layer "B.Fab")
		)
		(fp_line
			(start 0.9144 -0.508)
			(end -0.9144 -0.508)
			(stroke
				(width 0.1)
				(type default)
			)
			(layer "B.Fab")
		)
		(pad "1" smd rect
			(at 0.7366 0 180)
			(size 0.7112 0.8128)
			(layers "B.Cu" "B.Mask" "B.Paste")
			(net "P3V3_AUX")
		)
		(pad "2" smd rect
			(at -0.7366 0 180)
			(size 0.7112 0.8128)
			(layers "B.Cu" "B.Mask" "B.Paste")
			(net "P3V3_BMC_USB2AV33")
		)
	)
	(footprint ""
		(layer "B.Cu")
		(at 73.431908 -58.038492 -90)
		(property "Reference" "L15"
			(at 0 0 90)
			(layer "B.SilkS")
			(hide yes)
			(effects
				(font
					(size 1.27 1.27)
				)
				(justify mirror)
			)
		)
		(property "Value" ""
			(at 0 0 90)
			(layer "B.Fab")
			(effects
				(font
					(size 1.27 1.27)
				)
				(justify mirror)
			)
		)
		(duplicate_pad_numbers_are_jumpers no)
		(fp_line
			(start -1.27 0.5842)
			(end 1.27 0.5842)
			(stroke
				(width 0.1524)
				(type default)
			)
			(layer "B.SilkS")
		)
		(fp_line
			(start -1.27 0.5842)
			(end -1.27 -0.5842)
			(stroke
				(width 0.1524)
				(type default)
			)
			(layer "B.SilkS")
		)
		(fp_line
			(start -0.127 0.5842)
			(end -0.127 -0.5842)
			(stroke
				(width 0.1524)
				(type default)
			)
			(layer "B.SilkS")
		)
		(fp_line
			(start 0.127 0.5842)
			(end 0.127 -0.5842)
			(stroke
				(width 0.1524)
				(type default)
			)
			(layer "B.SilkS")
		)
		(fp_line
			(start 1.27 0.5842)
			(end 1.27 -0.5842)
			(stroke
				(width 0.1524)
				(type default)
			)
			(layer "B.SilkS")
		)
		(fp_line
			(start 1.27 -0.5588)
			(end 1.27 -0.5842)
			(stroke
				(width 0.1524)
				(type default)
			)
			(layer "B.SilkS")
		)
		(fp_line
			(start 1.27 -0.5842)
			(end -1.27 -0.5842)
			(stroke
				(width 0.1524)
				(type default)
			)
			(layer "B.SilkS")
		)
		(fp_line
			(start -0.9144 0.508)
			(end 0.9144 0.508)
			(stroke
				(width 0.1)
				(type default)
			)
			(layer "B.Fab")
		)
		(fp_line
			(start 0.9144 0.508)
			(end 0.9144 0.406654)
			(stroke
				(width 0.1)
				(type default)
			)
			(layer "B.Fab")
		)
		(fp_line
			(start 0.9144 0.406654)
			(end 1.194308 0.406654)
			(stroke
				(width 0.1)
				(type default)
			)
			(layer "B.Fab")
		)
		(fp_line
			(start 1.194308 0.406654)
			(end 1.194308 -0.406654)
			(stroke
				(width 0.1)
				(type default)
			)
			(layer "B.Fab")
		)
		(fp_line
			(start -1.1938 0.4064)
			(end -0.9144 0.4064)
			(stroke
				(width 0.1)
				(type default)
			)
			(layer "B.Fab")
		)
		(fp_line
			(start -0.9144 0.4064)
			(end -0.9144 0.508)
			(stroke
				(width 0.1)
				(type default)
			)
			(layer "B.Fab")
		)
		(fp_line
			(start -1.1938 -0.406654)
			(end -1.1938 0.4064)
			(stroke
				(width 0.1)
				(type default)
			)
			(layer "B.Fab")
		)
		(fp_line
			(start -0.9144 -0.406654)
			(end -1.1938 -0.406654)
			(stroke
				(width 0.1)
				(type default)
			)
			(layer "B.Fab")
		)
		(fp_line
			(start 0.9144 -0.406654)
			(end 0.9144 -0.508)
			(stroke
				(width 0.1)
				(type default)
			)
			(layer "B.Fab")
		)
		(fp_line
			(start 1.194308 -0.406654)
			(end 0.9144 -0.406654)
			(stroke
				(width 0.1)
				(type default)
			)
			(layer "B.Fab")
		)
		(fp_line
			(start -0.9144 -0.508)
			(end -0.9144 -0.406654)
			(stroke
				(width 0.1)
				(type default)
			)
			(layer "B.Fab")
		)
		(fp_line
			(start 0.9144 -0.508)
			(end -0.9144 -0.508)
			(stroke
				(width 0.1)
				(type default)
			)
			(layer "B.Fab")
		)
		(pad "1" smd rect
			(at 0.7366 0 180)
			(size 0.7112 0.8128)
			(layers "B.Cu" "B.Mask" "B.Paste")
			(net "P1V0_AUX")
		)
		(pad "2" smd rect
			(at -0.7366 0 180)
			(size 0.7112 0.8128)
			(layers "B.Cu" "B.Mask" "B.Paste")
			(net "P1V0_STBY_DP_VCC10A")
		)
	)
	(footprint ""
		(layer "B.Cu")
		(at 56.256174 -43.77436)
		(property "Reference" "C100"
			(at 0 0 0)
			(layer "B.SilkS")
			(hide yes)
			(effects
				(font
					(size 1.27 1.27)
				)
				(justify mirror)
			)
		)
		(property "Value" ""
			(at 0 0 0)
			(layer "B.Fab")
			(effects
				(font
					(size 1.27 1.27)
				)
				(justify mirror)
			)
		)
		(duplicate_pad_numbers_are_jumpers no)
		(fp_line
			(start -0.7874 -0.4064)
			(end -0.7874 0.4064)
			(stroke
				(width 0.1524)
				(type default)
			)
			(layer "B.SilkS")
		)
		(fp_line
			(start -0.7874 0.4064)
			(end 0.7874 0.4064)
			(stroke
				(width 0.1524)
				(type default)
			)
			(layer "B.SilkS")
		)
		(fp_line
			(start 0.7874 -0.4064)
			(end -0.7874 -0.4064)
			(stroke
				(width 0.1524)
				(type default)
			)
			(layer "B.SilkS")
		)
		(fp_line
			(start 0.7874 0.4064)
			(end 0.7874 -0.4064)
			(stroke
				(width 0.1524)
				(type default)
			)
			(layer "B.SilkS")
		)
		(fp_line
			(start -0.67945 -0.3048)
			(end -0.67945 0.3048)
			(stroke
				(width 0.1)
				(type default)
			)
			(layer "B.Fab")
		)
		(fp_line
			(start -0.67945 0.3048)
			(end -0.120396 0.3048)
			(stroke
				(width 0.1)
				(type default)
			)
			(layer "B.Fab")
		)
		(fp_line
			(start -0.12065 -0.3048)
			(end -0.67945 -0.3048)
			(stroke
				(width 0.1)
				(type default)
			)
			(layer "B.Fab")
		)
		(fp_line
			(start -0.12065 -0.2794)
			(end -0.12065 -0.3048)
			(stroke
				(width 0.1)
				(type default)
			)
			(layer "B.Fab")
		)
		(fp_line
			(start -0.120396 0.2794)
			(end 0.12065 0.2794)
			(stroke
				(width 0.1)
				(type default)
			)
			(layer "B.Fab")
		)
		(fp_line
			(start -0.120396 0.3048)
			(end -0.120396 0.2794)
			(stroke
				(width 0.1)
				(type default)
			)
			(layer "B.Fab")
		)
		(fp_line
			(start 0.12065 -0.305054)
			(end 0.12065 -0.2794)
			(stroke
				(width 0.1)
				(type default)
			)
			(layer "B.Fab")
		)
		(fp_line
			(start 0.12065 -0.2794)
			(end -0.12065 -0.2794)
			(stroke
				(width 0.1)
				(type default)
			)
			(layer "B.Fab")
		)
		(fp_line
			(start 0.12065 0.2794)
			(end 0.12065 0.3048)
			(stroke
				(width 0.1)
				(type default)
			)
			(layer "B.Fab")
		)
		(fp_line
			(start 0.12065 0.3048)
			(end 0.67945 0.3048)
			(stroke
				(width 0.1)
				(type default)
			)
			(layer "B.Fab")
		)
		(fp_line
			(start 0.67945 -0.305054)
			(end 0.12065 -0.305054)
			(stroke
				(width 0.1)
				(type default)
			)
			(layer "B.Fab")
		)
		(fp_line
			(start 0.67945 0.3048)
			(end 0.67945 -0.305054)
			(stroke
				(width 0.1)
				(type default)
			)
			(layer "B.Fab")
		)
		(pad "1" smd circle
			(at 0.40005 0 180)
			(size 0 0)
			(layers "B.Cu" "B.Mask" "B.Paste")
			(net "P1V8_AUX")
		)
		(pad "2" smd circle
			(at -0.40005 0 180)
			(size 0 0)
			(layers "B.Cu" "B.Mask" "B.Paste")
			(net "GND")
		)
	)
	(footprint ""
		(layer "B.Cu")
		(at 61.64326 -65.85585 -90)
		(property "Reference" "R469"
			(at 0 0 90)
			(layer "B.SilkS")
			(hide yes)
			(effects
				(font
					(size 1.27 1.27)
				)
				(justify mirror)
			)
		)
		(property "Value" ""
			(at 0 0 90)
			(layer "B.Fab")
			(effects
				(font
					(size 1.27 1.27)
				)
				(justify mirror)
			)
		)
		(duplicate_pad_numbers_are_jumpers no)
		(fp_line
			(start -0.7874 0.4064)
			(end 0.7874 0.4064)
			(stroke
				(width 0.1524)
				(type default)
			)
			(layer "B.SilkS")
		)
		(fp_line
			(start 0.7874 0.4064)
			(end 0.7874 -0.4064)
			(stroke
				(width 0.1524)
				(type default)
			)
			(layer "B.SilkS")
		)
		(fp_line
			(start -0.7874 -0.4064)
			(end -0.7874 0.4064)
			(stroke
				(width 0.1524)
				(type default)
			)
			(layer "B.SilkS")
		)
		(fp_line
			(start 0.7874 -0.4064)
			(end -0.7874 -0.4064)
			(stroke
				(width 0.1524)
				(type default)
			)
			(layer "B.SilkS")
		)
		(fp_line
			(start -0.67945 0.3048)
			(end -0.120396 0.3048)
			(stroke
				(width 0.1)
				(type default)
			)
			(layer "B.Fab")
		)
		(fp_line
			(start -0.120396 0.3048)
			(end -0.120396 0.2794)
			(stroke
				(width 0.1)
				(type default)
			)
			(layer "B.Fab")
		)
		(fp_line
			(start 0.12065 0.3048)
			(end 0.67945 0.3048)
			(stroke
				(width 0.1)
				(type default)
			)
			(layer "B.Fab")
		)
		(fp_line
			(start 0.67945 0.3048)
			(end 0.67945 -0.305054)
			(stroke
				(width 0.1)
				(type default)
			)
			(layer "B.Fab")
		)
		(fp_line
			(start -0.120396 0.2794)
			(end 0.12065 0.2794)
			(stroke
				(width 0.1)
				(type default)
			)
			(layer "B.Fab")
		)
		(fp_line
			(start 0.12065 0.2794)
			(end 0.12065 0.3048)
			(stroke
				(width 0.1)
				(type default)
			)
			(layer "B.Fab")
		)
		(fp_line
			(start -0.12065 -0.2794)
			(end -0.12065 -0.3048)
			(stroke
				(width 0.1)
				(type default)
			)
			(layer "B.Fab")
		)
		(fp_line
			(start 0.12065 -0.2794)
			(end -0.12065 -0.2794)
			(stroke
				(width 0.1)
				(type default)
			)
			(layer "B.Fab")
		)
		(fp_line
			(start -0.67945 -0.3048)
			(end -0.67945 0.3048)
			(stroke
				(width 0.1)
				(type default)
			)
			(layer "B.Fab")
		)
		(fp_line
			(start -0.12065 -0.3048)
			(end -0.67945 -0.3048)
			(stroke
				(width 0.1)
				(type default)
			)
			(layer "B.Fab")
		)
		(fp_line
			(start 0.12065 -0.305054)
			(end 0.12065 -0.2794)
			(stroke
				(width 0.1)
				(type default)
			)
			(layer "B.Fab")
		)
		(fp_line
			(start 0.67945 -0.305054)
			(end 0.12065 -0.305054)
			(stroke
				(width 0.1)
				(type default)
			)
			(layer "B.Fab")
		)
		(pad "1" smd circle
			(at 0.40005 0 90)
			(size 0 0)
			(layers "B.Cu" "B.Mask" "B.Paste")
			(net "SPI_BMC_TPM_MISO_R1")
		)
		(pad "2" smd circle
			(at -0.40005 0 90)
			(size 0 0)
			(layers "B.Cu" "B.Mask" "B.Paste")
			(net "SPI_BMC_TPM_MISO")
		)
	)
)
